FILE_TYPE=LIBRARY_PARTS;
primitive 'RT9818C44GV';
  pin
    'VDD':
      PIN_NUMBER='(3)';
      PINUSE='POWER';
      NO_LOAD_CHECK='Both';
      NO_IO_CHECK='Both';
      NO_ASSERT_CHECK='TRUE';
      NO_DIR_CHECK='TRUE';
      ALLOW_CONNECT='TRUE';
    'RESET#':
      PIN_NUMBER='(1)';
      OUTPUT_LOAD='(1.0,-1.0)';
    'GND':
      PIN_NUMBER='(2)';
      PINUSE='POWER';
      NO_LOAD_CHECK='Both';
      NO_IO_CHECK='Both';
      NO_ASSERT_CHECK='TRUE';
      NO_DIR_CHECK='TRUE';
      ALLOW_CONNECT='TRUE';
  end_pin;
  body
    PART_NAME='RT9818C44GV';
    BODY_NAME='RT9818C44GV';
    PHYS_DES_PREFIX='U';
    CLASS='IC';
  end_body;
end_primitive;

END.
